# SCM (Grand Teton) — schematic netlist excerpt (pin names and nets, part order shuffled) for the footprints in the layout excerpt that follows; sources: Cadence DE-HDL packaged netlist, KiCad conversion of 12092022_DA0F0TMDCD0_F0T_Management_Board_D_brd_V3_OCP.brd

R271  Q_RES  0 5% CHIP  pkg 0402LF  page 35 : A = RST_BMC_SELF_HW ; B = RST_BMC_SELF_HW_R2

(kicad_pcb
	(version 20260206)
	(generator "pcbnew")
	(generator_version "10.0")
	(general
		(thickness 1.6)
		(legacy_teardrops no)
	)
	(paper "A4")
	(title_block
		(title "12092022_DA0F0TMDCD0_F0T_Management_Board_D_brd_V3_OCP.brd")
		(comment 1 "Grand Teton / footprints 1220-1220 of 1440")
	)
	(layers
		(0 "F.Cu" signal "TOP")
		(4 "In1.Cu" signal "GND")
		(6 "In2.Cu" signal "IN1")
		(8 "In3.Cu" signal "GND1")
		(10 "In4.Cu" signal "IN2")
		(12 "In5.Cu" signal "VCC")
		(14 "In6.Cu" signal "VCC1")
		(16 "In7.Cu" signal "IN3")
		(18 "In8.Cu" signal "GND2")
		(20 "In9.Cu" signal "IN4")
		(22 "In10.Cu" signal "GND3")
		(2 "B.Cu" signal "BOTTOM")
		(9 "F.Adhes" user "F.Adhesive")
		(11 "B.Adhes" user "B.Adhesive")
		(13 "F.Paste" user "Package Geometry/Pastemask Top")
		(15 "B.Paste" user "Package Geometry/Pastemask Bottom")
		(5 "F.SilkS" user "Ref Des/Silkscreen Top")
		(7 "B.SilkS" user "Ref Des/Silkscreen Bottom")
		(1 "F.Mask" user "Board Geometry/Soldermask Top")
		(3 "B.Mask" user "Board Geometry/Soldermask Bottom")
		(17 "Dwgs.User" user "User.Drawings")
		(19 "Cmts.User" user "User.Comments")
		(21 "Eco1.User" user "User.Eco1")
		(23 "Eco2.User" user "User.Eco2")
		(25 "Edge.Cuts" user "Board Geometry/Outline")
		(27 "Margin" user)
		(31 "F.CrtYd" user "Package Geometry/Place Bound Top")
		(29 "B.CrtYd" user "Package Geometry/Place Bound Bottom")
		(35 "F.Fab" user "Ref Des/Assembly Top")
		(33 "B.Fab" user "Ref Des/Assembly Bottom")
	)
	(footprint ""
		(layer "B.Cu")
		(at 12.319 -91.44 180)
		(property "Reference" "R271"
			(at 0 0 0)
			(layer "B.SilkS")
			(hide yes)
			(effects
				(font
					(size 1.27 1.27)
				)
				(justify mirror)
			)
		)
		(property "Value" ""
			(at 0 0 0)
			(layer "B.Fab")
			(effects
				(font
					(size 1.27 1.27)
				)
				(justify mirror)
			)
		)
		(duplicate_pad_numbers_are_jumpers no)
		(fp_line
			(start 0.7874 0.4064)
			(end 0.7874 -0.4064)
			(stroke
				(width 0.1524)
				(type default)
			)
			(layer "B.SilkS")
		)
		(fp_line
			(start 0.7874 -0.4064)
			(end -0.7874 -0.4064)
			(stroke
				(width 0.1524)
				(type default)
			)
			(layer "B.SilkS")
		)
		(fp_line
			(start -0.7874 0.4064)
			(end 0.7874 0.4064)
			(stroke
				(width 0.1524)
				(type default)
			)
			(layer "B.SilkS")
		)
		(fp_line
			(start -0.7874 -0.4064)
			(end -0.7874 0.4064)
			(stroke
				(width 0.1524)
				(type default)
			)
			(layer "B.SilkS")
		)
		(fp_line
			(start 0.67945 0.3048)
			(end 0.67945 -0.305054)
			(stroke
				(width 0.1)
				(type default)
			)
			(layer "B.Fab")
		)
		(fp_line
			(start 0.67945 -0.305054)
			(end 0.12065 -0.305054)
			(stroke
				(width 0.1)
				(type default)
			)
			(layer "B.Fab")
		)
		(fp_line
			(start 0.12065 0.3048)
			(end 0.67945 0.3048)
			(stroke
				(width 0.1)
				(type default)
			)
			(layer "B.Fab")
		)
		(fp_line
			(start 0.12065 0.2794)
			(end 0.12065 0.3048)
			(stroke
				(width 0.1)
				(type default)
			)
			(layer "B.Fab")
		)
		(fp_line
			(start 0.12065 -0.2794)
			(end -0.12065 -0.2794)
			(stroke
				(width 0.1)
				(type default)
			)
			(layer "B.Fab")
		)
		(fp_line
			(start 0.12065 -0.305054)
			(end 0.12065 -0.2794)
			(stroke
				(width 0.1)
				(type default)
			)
			(layer "B.Fab")
		)
		(fp_line
			(start -0.120396 0.3048)
			(end -0.120396 0.2794)
			(stroke
				(width 0.1)
				(type default)
			)
			(layer "B.Fab")
		)
		(fp_line
			(start -0.120396 0.2794)
			(end 0.12065 0.2794)
			(stroke
				(width 0.1)
				(type default)
			)
			(layer "B.Fab")
		)
		(fp_line
			(start -0.12065 -0.2794)
			(end -0.12065 -0.3048)
			(stroke
				(width 0.1)
				(type default)
			)
			(layer "B.Fab")
		)
		(fp_line
			(start -0.12065 -0.3048)
			(end -0.67945 -0.3048)
			(stroke
				(width 0.1)
				(type default)
			)
			(layer "B.Fab")
		)
		(fp_line
			(start -0.67945 0.3048)
			(end -0.120396 0.3048)
			(stroke
				(width 0.1)
				(type default)
			)
			(layer "B.Fab")
		)
		(fp_line
			(start -0.67945 -0.3048)
			(end -0.67945 0.3048)
			(stroke
				(width 0.1)
				(type default)
			)
			(layer "B.Fab")
		)
		(pad "1" smd circle
			(at 0.40005 0)
			(size 0 0)
			(layers "B.Cu" "B.Mask" "B.Paste")
			(net "RST_BMC_SELF_HW")
		)
		(pad "2" smd circle
			(at -0.40005 0)
			(size 0 0)
			(layers "B.Cu" "B.Mask" "B.Paste")
			(net "RST_BMC_SELF_HW_R2")
		)
	)
)
